(kicad_pcb
	(version 20241229)
	(generator "pcbnew")
	(generator_version "9.0")
	(general
		(thickness 1.599998)
		(legacy_teardrops no)
	)
	(paper "A4")
	(title_block
		(title "Artix - Datacenter Secure Control Module (DC-SCM)")
		(date "2024-11-06")
		(rev "1.1.3")
		(comment 9 "footprints 235-239 of 544")
	)
	(layers
		(0 "F.Cu" signal)
		(4 "In1.Cu" signal)
		(6 "In2.Cu" signal)
		(8 "In3.Cu" signal)
		(10 "In4.Cu" signal)
		(12 "In5.Cu" signal)
		(14 "In6.Cu" signal)
		(2 "B.Cu" signal)
		(9 "F.Adhes" user "F.Adhesive")
		(11 "B.Adhes" user "B.Adhesive")
		(13 "F.Paste" user)
		(15 "B.Paste" user)
		(5 "F.SilkS" user "F.Silkscreen")
		(7 "B.SilkS" user "B.Silkscreen")
		(1 "F.Mask" user)
		(3 "B.Mask" user)
		(17 "Dwgs.User" user "User.Drawings")
		(19 "Cmts.User" user "User.Comments")
		(21 "Eco1.User" user "User.Eco1")
		(23 "Eco2.User" user "User.Eco2")
		(25 "Edge.Cuts" user)
		(27 "Margin" user)
		(31 "F.CrtYd" user "F.Courtyard")
		(29 "B.CrtYd" user "B.Courtyard")
		(35 "F.Fab" user)
		(33 "B.Fab" user)
	)
	(footprint "antmicro-footprints:Resonator_SMD_Abracon_ABM8G_3.2x2.5mm"
		(layer "F.Cu")
		(at 110.91 95.18 90)
		(property "Reference" "Y2"
			(at 2.08 1.69 180)
			(layer "F.SilkS")
			(effects
				(font
					(size 0.7 0.7)
					(thickness 0.15)
				)
				(justify right bottom)
			)
		)
		(property "Value" "Resonator_25MHz_ABM8G"
			(at -1.75 2.548 90)
			(layer "F.Fab")
			(effects
				(font
					(size 0.7 0.7)
					(thickness 0.15)
				)
				(justify left bottom)
			)
		)
		(property "Datasheet" "https://abracon.com/Resonators/ABM8G.pdf"
			(at 0 0 90)
			(layer "F.Fab")
			(hide yes)
			(effects
				(font
					(size 1.27 1.27)
					(thickness 0.15)
				)
			)
		)
		(property "Description" "Crystal, 25 MHz, SMD, 3.2mm x 2.5mm, 30 ppm, 18 pF, 20 ppm, ABM8G"
			(at 0 0 90)
			(layer "F.Fab")
			(hide yes)
			(effects
				(font
					(size 1.27 1.27)
					(thickness 0.15)
				)
			)
		)
		(property "Author" "Antmicro"
			(at 206.09 -15.73 0)
			(layer "F.Fab")
			(hide yes)
			(effects
				(font
					(size 1 1)
					(thickness 0.15)
				)
			)
		)
		(property "License" "Apache-2.0"
			(at 206.09 -15.73 0)
			(layer "F.Fab")
			(hide yes)
			(effects
				(font
					(size 1 1)
					(thickness 0.15)
				)
			)
		)
		(property "MPN" "ABM8G-25.000MHZ-18-D2Y-T3"
			(at 206.09 -15.73 0)
			(layer "F.Fab")
			(hide yes)
			(effects
				(font
					(size 1 1)
					(thickness 0.15)
				)
			)
		)
		(property "Manufacturer" "Abracon"
			(at 206.09 -15.73 0)
			(layer "F.Fab")
			(hide yes)
			(effects
				(font
					(size 1 1)
					(thickness 0.15)
				)
			)
		)
		(property "Val" "25 MHz"
			(at 206.09 -15.73 0)
			(layer "F.Fab")
			(hide yes)
			(effects
				(font
					(size 1 1)
					(thickness 0.15)
				)
			)
		)
		(sheetname "/Ethernet/")
		(sheetfile "ethernet.kicad_sch")
		(attr smd)
		(fp_line
			(start -0.35 -1.25)
			(end 0.45 -1.25)
			(stroke
				(width 0.15)
				(type solid)
			)
			(layer "F.SilkS")
		)
		(fp_line
			(start 1.6 0.3)
			(end 1.6 -0.2)
			(stroke
				(width 0.15)
				(type solid)
			)
			(layer "F.SilkS")
		)
		(fp_line
			(start -1.6 0.3)
			(end -1.6 -0.2)
			(stroke
				(width 0.15)
				(type solid)
			)
			(layer "F.SilkS")
		)
		(fp_line
			(start -0.35 1.25)
			(end 0.45 1.25)
			(stroke
				(width 0.15)
				(type solid)
			)
			(layer "F.SilkS")
		)
		(fp_circle
			(center -1.75 1.5)
			(end -1.7 1.5)
			(stroke
				(width 0.15)
				(type solid)
			)
			(fill no)
			(layer "F.SilkS")
		)
		(fp_rect
			(start -1.907 -1.55)
			(end 2.006 1.649)
			(stroke
				(width 0.05)
				(type solid)
			)
			(fill no)
			(layer "F.CrtYd")
		)
		(pad "1" smd roundrect
			(at -1.101 0.949 90)
			(size 1.3 1.1)
			(layers "F.Cu" "F.Mask" "F.Paste")
			(roundrect_rratio 0)
			(chamfer_ratio 0.2)
			(chamfer bottom_left)
			(net 199 "Net-(U20-XO)")
			(pintype "passive")
		)
		(pad "2" smd rect
			(at 1.199 0.949 90)
			(size 1.3 1.1)
			(layers "F.Cu" "F.Mask" "F.Paste")
			(net 1 "GND")
			(pinfunction "SH")
			(pintype "passive")
		)
		(pad "3" smd rect
			(at 1.199 -0.85 90)
			(size 1.3 1.1)
			(layers "F.Cu" "F.Mask" "F.Paste")
			(net 201 "Net-(U20-XI)")
			(pintype "passive")
		)
		(pad "4" smd rect
			(at -1.101 -0.85 90)
			(size 1.3 1.1)
			(layers "F.Cu" "F.Mask" "F.Paste")
			(net 1 "GND")
			(pinfunction "SH")
			(pintype "passive")
		)
	)
	(footprint "antmicro-footprints:C_0402_1005Metric"
		(layer "F.Cu")
		(at 141.35 91.7125 180)
		(descr "Capacitor SMD 0402")
		(tags "capacitor SMD 0402")
		(property "Reference" "C6"
			(at -2.25 -0.2875 0)
			(layer "F.SilkS")
			(effects
				(font
					(size 0.7 0.7)
					(thickness 0.15)
				)
				(justify right bottom)
			)
		)
		(property "Value" "C_100n_0402"
			(at 0 1.4 0)
			(layer "F.Fab")
			(effects
				(font
					(size 0.7 0.7)
					(thickness 0.15)
				)
				(justify right bottom)
			)
		)
		(property "Datasheet" "https://www.murata.com/products/productdetail?partno=GRM155R61H104KE14%23"
			(at 0 0 180)
			(layer "F.Fab")
			(hide yes)
			(effects
				(font
					(size 1.27 1.27)
					(thickness 0.15)
				)
			)
		)
		(property "Description" "SMD Multilayer Ceramic Capacitor, 0.1 µF, 50 V, 0402 [1005 Metric], ± 10%, X5R, GRM Series"
			(at 0 0 180)
			(layer "F.Fab")
			(hide yes)
			(effects
				(font
					(size 1.27 1.27)
					(thickness 0.15)
				)
			)
		)
		(property "Author" "Antmicro"
			(at 282.7 183.425 0)
			(layer "F.Fab")
			(hide yes)
			(effects
				(font
					(size 1 1)
					(thickness 0.15)
				)
			)
		)
		(property "Dielectric" "X5R"
			(at 282.7 183.425 0)
			(layer "F.Fab")
			(hide yes)
			(effects
				(font
					(size 1 1)
					(thickness 0.15)
				)
			)
		)
		(property "License" "Apache-2.0"
			(at 282.7 183.425 0)
			(layer "F.Fab")
			(hide yes)
			(effects
				(font
					(size 1 1)
					(thickness 0.15)
				)
			)
		)
		(property "MPN" "GRM155R61H104KE14D"
			(at 282.7 183.425 0)
			(layer "F.Fab")
			(hide yes)
			(effects
				(font
					(size 1 1)
					(thickness 0.15)
				)
			)
		)
		(property "Manufacturer" "Murata"
			(at 282.7 183.425 0)
			(layer "F.Fab")
			(hide yes)
			(effects
				(font
					(size 1 1)
					(thickness 0.15)
				)
			)
		)
		(property "Val" "100n"
			(at 282.7 183.425 0)
			(layer "F.Fab")
			(hide yes)
			(effects
				(font
					(size 1 1)
					(thickness 0.15)
				)
			)
		)
		(property "Voltage" "50V"
			(at 282.7 183.425 0)
			(layer "F.Fab")
			(hide yes)
			(effects
				(font
					(size 1 1)
					(thickness 0.15)
				)
			)
		)
		(sheetname "/Interfaces/")
		(sheetfile "interfaces.kicad_sch")
		(attr smd)
		(fp_rect
			(start -0.925 -0.47)
			(end 0.925 0.47)
			(stroke
				(width 0.05)
				(type default)
			)
			(fill no)
			(layer "F.CrtYd")
		)
		(fp_line
			(start 0.504 0.248)
			(end -0.494 0.248)
			(stroke
				(width 0.15)
				(type solid)
			)
			(layer "F.Fab")
		)
		(fp_line
			(start 0.504 -0.25)
			(end 0.504 0.248)
			(stroke
				(width 0.15)
				(type solid)
			)
			(layer "F.Fab")
		)
		(fp_line
			(start -0.494 0.248)
			(end -0.494 -0.25)
			(stroke
				(width 0.15)
				(type solid)
			)
			(layer "F.Fab")
		)
		(fp_line
			(start -0.494 -0.25)
			(end 0.504 -0.25)
			(stroke
				(width 0.15)
				(type solid)
			)
			(layer "F.Fab")
		)
		(pad "1" smd roundrect
			(at -0.48 0 180)
			(size 0.59 0.64)
			(layers "F.Cu" "F.Mask" "F.Paste")
			(roundrect_rratio 0.25)
			(net 1 "GND")
			(pintype "passive")
		)
		(pad "2" smd roundrect
			(at 0.48 0 180)
			(size 0.59 0.64)
			(layers "F.Cu" "F.Mask" "F.Paste")
			(roundrect_rratio 0.25)
			(net 597 "1V8_FT")
			(pintype "passive")
		)
	)
	(footprint "antmicro-footprints:C_0402_1005Metric"
		(layer "F.Cu")
		(at 141.35 99.0125 180)
		(descr "Capacitor SMD 0402")
		(tags "capacitor SMD 0402")
		(property "Reference" "C7"
			(at -2.35 -0.2875 0)
			(layer "F.SilkS")
			(effects
				(font
					(size 0.7 0.7)
					(thickness 0.15)
				)
				(justify right bottom)
			)
		)
		(property "Value" "C_100n_0402"
			(at 0 1.4 0)
			(layer "F.Fab")
			(effects
				(font
					(size 0.7 0.7)
					(thickness 0.15)
				)
				(justify right bottom)
			)
		)
		(property "Datasheet" "https://www.murata.com/products/productdetail?partno=GRM155R61H104KE14%23"
			(at 0 0 180)
			(layer "F.Fab")
			(hide yes)
			(effects
				(font
					(size 1.27 1.27)
					(thickness 0.15)
				)
			)
		)
		(property "Description" "SMD Multilayer Ceramic Capacitor, 0.1 µF, 50 V, 0402 [1005 Metric], ± 10%, X5R, GRM Series"
			(at 0 0 180)
			(layer "F.Fab")
			(hide yes)
			(effects
				(font
					(size 1.27 1.27)
					(thickness 0.15)
				)
			)
		)
		(property "Author" "Antmicro"
			(at 282.7 198.025 0)
			(layer "F.Fab")
			(hide yes)
			(effects
				(font
					(size 1 1)
					(thickness 0.15)
				)
			)
		)
		(property "Dielectric" "X5R"
			(at 282.7 198.025 0)
			(layer "F.Fab")
			(hide yes)
			(effects
				(font
					(size 1 1)
					(thickness 0.15)
				)
			)
		)
		(property "License" "Apache-2.0"
			(at 282.7 198.025 0)
			(layer "F.Fab")
			(hide yes)
			(effects
				(font
					(size 1 1)
					(thickness 0.15)
				)
			)
		)
		(property "MPN" "GRM155R61H104KE14D"
			(at 282.7 198.025 0)
			(layer "F.Fab")
			(hide yes)
			(effects
				(font
					(size 1 1)
					(thickness 0.15)
				)
			)
		)
		(property "Manufacturer" "Murata"
			(at 282.7 198.025 0)
			(layer "F.Fab")
			(hide yes)
			(effects
				(font
					(size 1 1)
					(thickness 0.15)
				)
			)
		)
		(property "Val" "100n"
			(at 282.7 198.025 0)
			(layer "F.Fab")
			(hide yes)
			(effects
				(font
					(size 1 1)
					(thickness 0.15)
				)
			)
		)
		(property "Voltage" "50V"
			(at 282.7 198.025 0)
			(layer "F.Fab")
			(hide yes)
			(effects
				(font
					(size 1 1)
					(thickness 0.15)
				)
			)
		)
		(sheetname "/Interfaces/")
		(sheetfile "interfaces.kicad_sch")
		(attr smd)
		(fp_rect
			(start -0.925 -0.47)
			(end 0.925 0.47)
			(stroke
				(width 0.05)
				(type default)
			)
			(fill no)
			(layer "F.CrtYd")
		)
		(fp_line
			(start 0.504 0.248)
			(end -0.494 0.248)
			(stroke
				(width 0.15)
				(type solid)
			)
			(layer "F.Fab")
		)
		(fp_line
			(start 0.504 -0.25)
			(end 0.504 0.248)
			(stroke
				(width 0.15)
				(type solid)
			)
			(layer "F.Fab")
		)
		(fp_line
			(start -0.494 0.248)
			(end -0.494 -0.25)
			(stroke
				(width 0.15)
				(type solid)
			)
			(layer "F.Fab")
		)
		(fp_line
			(start -0.494 -0.25)
			(end 0.504 -0.25)
			(stroke
				(width 0.15)
				(type solid)
			)
			(layer "F.Fab")
		)
		(pad "1" smd roundrect
			(at -0.48 0 180)
			(size 0.59 0.64)
			(layers "F.Cu" "F.Mask" "F.Paste")
			(roundrect_rratio 0.25)
			(net 1 "GND")
			(pintype "passive")
		)
		(pad "2" smd roundrect
			(at 0.48 0 180)
			(size 0.59 0.64)
			(layers "F.Cu" "F.Mask" "F.Paste")
			(roundrect_rratio 0.25)
			(net 597 "1V8_FT")
			(pintype "passive")
		)
	)
	(footprint "antmicro-footprints:C_0402_1005Metric"
		(layer "F.Cu")
		(at 132.85 101.8125 90)
		(descr "Capacitor SMD 0402")
		(tags "capacitor SMD 0402")
		(property "Reference" "C107"
			(at -3.6875 0.45 90)
			(layer "F.SilkS")
			(effects
				(font
					(size 0.7 0.7)
					(thickness 0.15)
				)
				(justify left bottom)
			)
		)
		(property "Value" "C_100n_0402"
			(at 0 1.4 90)
			(layer "F.Fab")
			(effects
				(font
					(size 0.7 0.7)
					(thickness 0.15)
				)
				(justify left bottom)
			)
		)
		(property "Datasheet" "https://www.murata.com/products/productdetail?partno=GRM155R61H104KE14%23"
			(at 0 0 90)
			(layer "F.Fab")
			(hide yes)
			(effects
				(font
					(size 1.27 1.27)
					(thickness 0.15)
				)
			)
		)
		(property "Description" "SMD Multilayer Ceramic Capacitor, 0.1 µF, 50 V, 0402 [1005 Metric], ± 10%, X5R, GRM Series"
			(at 0 0 90)
			(layer "F.Fab")
			(hide yes)
			(effects
				(font
					(size 1.27 1.27)
					(thickness 0.15)
				)
			)
		)
		(property "Author" "Antmicro"
			(at 234.6625 -31.0375 0)
			(layer "F.Fab")
			(hide yes)
			(effects
				(font
					(size 1 1)
					(thickness 0.15)
				)
			)
		)
		(property "Dielectric" "X5R"
			(at 234.6625 -31.0375 0)
			(layer "F.Fab")
			(hide yes)
			(effects
				(font
					(size 1 1)
					(thickness 0.15)
				)
			)
		)
		(property "License" "Apache-2.0"
			(at 234.6625 -31.0375 0)
			(layer "F.Fab")
			(hide yes)
			(effects
				(font
					(size 1 1)
					(thickness 0.15)
				)
			)
		)
		(property "MPN" "GRM155R61H104KE14D"
			(at 234.6625 -31.0375 0)
			(layer "F.Fab")
			(hide yes)
			(effects
				(font
					(size 1 1)
					(thickness 0.15)
				)
			)
		)
		(property "Manufacturer" "Murata"
			(at 234.6625 -31.0375 0)
			(layer "F.Fab")
			(hide yes)
			(effects
				(font
					(size 1 1)
					(thickness 0.15)
				)
			)
		)
		(property "Val" "100n"
			(at 234.6625 -31.0375 0)
			(layer "F.Fab")
			(hide yes)
			(effects
				(font
					(size 1 1)
					(thickness 0.15)
				)
			)
		)
		(property "Voltage" "50V"
			(at 234.6625 -31.0375 0)
			(layer "F.Fab")
			(hide yes)
			(effects
				(font
					(size 1 1)
					(thickness 0.15)
				)
			)
		)
		(sheetname "/Interfaces/")
		(sheetfile "interfaces.kicad_sch")
		(attr smd)
		(fp_rect
			(start -0.925 -0.47)
			(end 0.925 0.47)
			(stroke
				(width 0.05)
				(type default)
			)
			(fill no)
			(layer "F.CrtYd")
		)
		(fp_line
			(start 0.504 -0.25)
			(end 0.504 0.248)
			(stroke
				(width 0.15)
				(type solid)
			)
			(layer "F.Fab")
		)
		(fp_line
			(start -0.494 -0.25)
			(end 0.504 -0.25)
			(stroke
				(width 0.15)
				(type solid)
			)
			(layer "F.Fab")
		)
		(fp_line
			(start 0.504 0.248)
			(end -0.494 0.248)
			(stroke
				(width 0.15)
				(type solid)
			)
			(layer "F.Fab")
		)
		(fp_line
			(start -0.494 0.248)
			(end -0.494 -0.25)
			(stroke
				(width 0.15)
				(type solid)
			)
			(layer "F.Fab")
		)
		(pad "1" smd roundrect
			(at -0.48 0 90)
			(size 0.59 0.64)
			(layers "F.Cu" "F.Mask" "F.Paste")
			(roundrect_rratio 0.25)
			(net 1 "GND")
			(pintype "passive")
		)
		(pad "2" smd roundrect
			(at 0.48 0 90)
			(size 0.59 0.64)
			(layers "F.Cu" "F.Mask" "F.Paste")
			(roundrect_rratio 0.25)
			(net 597 "1V8_FT")
			(pintype "passive")
		)
	)
	(footprint "antmicro-footprints:C_0402_1005Metric"
		(layer "F.Cu")
		(at 133.45 88.7125 -90)
		(descr "Capacitor SMD 0402")
		(tags "capacitor SMD 0402")
		(property "Reference" "C149"
			(at -3.7125 -0.35 90)
			(layer "F.SilkS")
			(effects
				(font
					(size 0.7 0.7)
					(thickness 0.15)
				)
				(justify right bottom)
			)
		)
		(property "Value" "C_100n_0402"
			(at 0 1.4 90)
			(layer "F.Fab")
			(effects
				(font
					(size 0.7 0.7)
					(thickness 0.15)
				)
				(justify right bottom)
			)
		)
		(property "Datasheet" "https://www.murata.com/products/productdetail?partno=GRM155R61H104KE14%23"
			(at 0 0 270)
			(layer "F.Fab")
			(hide yes)
			(effects
				(font
					(size 1.27 1.27)
					(thickness 0.15)
				)
			)
		)
		(property "Description" "SMD Multilayer Ceramic Capacitor, 0.1 µF, 50 V, 0402 [1005 Metric], ± 10%, X5R, GRM Series"
			(at 0 0 270)
			(layer "F.Fab")
			(hide yes)
			(effects
				(font
					(size 1.27 1.27)
					(thickness 0.15)
				)
			)
		)
		(property "Author" "Antmicro"
			(at 44.7375 222.1625 0)
			(layer "F.Fab")
			(hide yes)
			(effects
				(font
					(size 1 1)
					(thickness 0.15)
				)
			)
		)
		(property "Dielectric" "X5R"
			(at 44.7375 222.1625 0)
			(layer "F.Fab")
			(hide yes)
			(effects
				(font
					(size 1 1)
					(thickness 0.15)
				)
			)
		)
		(property "License" "Apache-2.0"
			(at 44.7375 222.1625 0)
			(layer "F.Fab")
			(hide yes)
			(effects
				(font
					(size 1 1)
					(thickness 0.15)
				)
			)
		)
		(property "MPN" "GRM155R61H104KE14D"
			(at 44.7375 222.1625 0)
			(layer "F.Fab")
			(hide yes)
			(effects
				(font
					(size 1 1)
					(thickness 0.15)
				)
			)
		)
		(property "Manufacturer" "Murata"
			(at 44.7375 222.1625 0)
			(layer "F.Fab")
			(hide yes)
			(effects
				(font
					(size 1 1)
					(thickness 0.15)
				)
			)
		)
		(property "Val" "100n"
			(at 44.7375 222.1625 0)
			(layer "F.Fab")
			(hide yes)
			(effects
				(font
					(size 1 1)
					(thickness 0.15)
				)
			)
		)
		(property "Voltage" "50V"
			(at 44.7375 222.1625 0)
			(layer "F.Fab")
			(hide yes)
			(effects
				(font
					(size 1 1)
					(thickness 0.15)
				)
			)
		)
		(sheetname "/Interfaces/")
		(sheetfile "interfaces.kicad_sch")
		(attr smd)
		(fp_rect
			(start -0.925 -0.47)
			(end 0.925 0.47)
			(stroke
				(width 0.05)
				(type default)
			)
			(fill no)
			(layer "F.CrtYd")
		)
		(fp_line
			(start -0.494 0.248)
			(end -0.494 -0.25)
			(stroke
				(width 0.15)
				(type solid)
			)
			(layer "F.Fab")
		)
		(fp_line
			(start 0.504 0.248)
			(end -0.494 0.248)
			(stroke
				(width 0.15)
				(type solid)
			)
			(layer "F.Fab")
		)
		(fp_line
			(start -0.494 -0.25)
			(end 0.504 -0.25)
			(stroke
				(width 0.15)
				(type solid)
			)
			(layer "F.Fab")
		)
		(fp_line
			(start 0.504 -0.25)
			(end 0.504 0.248)
			(stroke
				(width 0.15)
				(type solid)
			)
			(layer "F.Fab")
		)
		(pad "1" smd roundrect
			(at -0.48 0 270)
			(size 0.59 0.64)
			(layers "F.Cu" "F.Mask" "F.Paste")
			(roundrect_rratio 0.25)
			(net 1 "GND")
			(pintype "passive")
		)
		(pad "2" smd roundrect
			(at 0.48 0 270)
			(size 0.59 0.64)
			(layers "F.Cu" "F.Mask" "F.Paste")
			(roundrect_rratio 0.25)
			(net 116 "/Interfaces/FT_VPLL")
			(pintype "passive")
		)
	)
)
